# BASEBOARD_FAB2 (Tioga Pass) — schematic netlist excerpt (pin names and nets, part order shuffled) for the footprints in the layout excerpt that follows; sources: Cadence DE-HDL packaged netlist, KiCad conversion of Wiwynn_Tioga_Pass_MB.brd

SH7U1  SHUNT  EMPTY  pkg SH0201  page 225 : A = VSENSE_PVDDQ_GHJ_P ; B = PVDDQ_GHJ
R7W3  RES  10.0K 1% EMPTY  pkg 0402  page 166 : A = P3V3_STBY ; B = PECI_SEL
C22W2  SC22U16V5MX-4-GP  20%  pkg SMD-BCG5  page 225 : \1\ = VR_FET_SW_P12V_STBY_PVDDQ_GHJ ; \2\ = GND

(kicad_pcb
	(version 20260206)
	(generator "pcbnew")
	(generator_version "10.0")
	(general
		(thickness 1.6)
		(legacy_teardrops no)
	)
	(paper "A4")
	(title_block
		(title "Wiwynn_Tioga_Pass_MB.brd")
		(comment 1 "Tioga Pass / footprints 3028-3030 of 4770")
	)
	(layers
		(0 "F.Cu" signal "TOP")
		(4 "In1.Cu" signal "L2GND")
		(6 "In2.Cu" signal "L3")
		(8 "In3.Cu" signal "L4GND")
		(10 "In4.Cu" signal "L5")
		(12 "In5.Cu" signal "L6GND")
		(14 "In6.Cu" signal "L7VCC")
		(16 "In7.Cu" signal "L8VCC")
		(18 "In8.Cu" signal "L9GND")
		(20 "In9.Cu" signal "L10")
		(22 "In10.Cu" signal "L11GND")
		(24 "In11.Cu" signal "L12")
		(26 "In12.Cu" signal "L13GND")
		(2 "B.Cu" signal "BOTTOM")
		(9 "F.Adhes" user "F.Adhesive")
		(11 "B.Adhes" user "B.Adhesive")
		(13 "F.Paste" user "Package Geometry/Pastemask Top")
		(15 "B.Paste" user "Package Geometry/Pastemask Bottom")
		(5 "F.SilkS" user "Ref Des/Silkscreen Top")
		(7 "B.SilkS" user "Ref Des/Silkscreen Bottom")
		(1 "F.Mask" user "Board Geometry/Soldermask Top")
		(3 "B.Mask" user "Board Geometry/Soldermask Bottom")
		(17 "Dwgs.User" user "User.Drawings")
		(19 "Cmts.User" user "User.Comments")
		(21 "Eco1.User" user "User.Eco1")
		(23 "Eco2.User" user "User.Eco2")
		(25 "Edge.Cuts" user "Board Geometry/Outline")
		(27 "Margin" user)
		(31 "F.CrtYd" user "Package Geometry/Place Bound Top")
		(29 "B.CrtYd" user "Package Geometry/Place Bound Bottom")
		(35 "F.Fab" user "Ref Des/Assembly Top")
		(33 "B.Fab" user "Ref Des/Assembly Bottom")
	)
	(footprint ""
		(layer "B.Cu")
		(at -3.1242 -6.4008 -90)
		(property "Reference" "C22W2"
			(at 0 0 90)
			(layer "B.SilkS")
			(hide yes)
			(effects
				(font
					(size 1.27 1.27)
				)
				(justify mirror)
			)
		)
		(property "Value" "*"
			(at 0.0762 -6.2357 270)
			(unlocked yes)
			(layer "B.Fab")
			(hide yes)
			(effects
				(font
					(size 1.27 1.016)
					(thickness 0.1524)
				)
				(justify mirror)
			)
		)
		(property "Device Type" "SC22U16V5MX-4-GP_SMD-BCG5-SC22A"
			(at 0.0762 -8.2677 270)
			(unlocked yes)
			(layer "B.Fab")
			(hide yes)
			(effects
				(font
					(size 1.27 1.016)
					(thickness 0.1524)
				)
				(justify mirror)
			)
		)
		(duplicate_pad_numbers_are_jumpers no)
		(fp_line
			(start -0.635 0)
			(end 0.635 0)
			(stroke
				(width 0.508)
				(type default)
			)
			(layer "B.SilkS")
		)
		(fp_rect
			(start 0.9652 1.778)
			(end -0.9652 -1.778)
			(stroke
				(width 0)
				(type default)
			)
			(fill no)
			(layer "B.CrtYd")
		)
		(fp_poly
			(pts
				(xy 0.9652 -1.778) (xy -0.9652 -1.778) (xy -0.9652 1.778) (xy 0.9652 1.778)
			)
			(stroke
				(width 0)
				(type default)
			)
			(fill no)
			(layer "B.Fab")
		)
		(pad "1" smd rect
			(at 0 -0.9652 90)
			(size 1.397 1.143)
			(layers "B.Cu" "B.Mask" "B.Paste")
			(net "VR_FET_SW_P12V_STBY_PVDDQ_GHJ")
		)
		(pad "2" smd rect
			(at 0 0.9652 90)
			(size 1.397 1.143)
			(layers "B.Cu" "B.Mask" "B.Paste")
			(net "GND")
		)
	)
	(footprint ""
		(layer "B.Cu")
		(at 111.094012 -29.94152 -90)
		(property "Reference" "SH7U1"
			(at 0 0 90)
			(layer "B.SilkS")
			(hide yes)
			(effects
				(font
					(size 1.27 1.27)
				)
				(justify mirror)
			)
		)
		(property "Value" ""
			(at 0 0 90)
			(layer "B.Fab")
			(effects
				(font
					(size 1.27 1.27)
				)
				(justify mirror)
			)
		)
		(duplicate_pad_numbers_are_jumpers no)
		(fp_poly
			(pts
				(xy 0.1651 -0.0508) (xy 0.1651 0.5842) (xy -0.1651 0.5842) (xy -0.1651 -0.0508)
			)
			(stroke
				(width 0)
				(type default)
			)
			(fill no)
			(layer "B.CrtYd")
		)
		(fp_line
			(start -0.1651 0.5842)
			(end 0.1651 0.5842)
			(stroke
				(width 0.1)
				(type default)
			)
			(layer "B.Fab")
		)
		(fp_line
			(start 0.1651 0.5842)
			(end 0.1651 -0.0508)
			(stroke
				(width 0.1)
				(type default)
			)
			(layer "B.Fab")
		)
		(fp_line
			(start -0.1651 -0.0508)
			(end -0.1651 0.5842)
			(stroke
				(width 0.1)
				(type default)
			)
			(layer "B.Fab")
		)
		(fp_line
			(start 0.1651 -0.0508)
			(end -0.1651 -0.0508)
			(stroke
				(width 0.1)
				(type default)
			)
			(layer "B.Fab")
		)
		(pad "1" smd custom
			(at 0 0 270)
			(size 0.0762 0.0762)
			(layers "B.Cu" "B.Mask" "B.Paste")
			(net "VSENSE_PVDDQ_GHJ_P")
			(options
				(clearance outline)
				(anchor circle)
			)
			(primitives
				(gr_poly
					(pts
						(arc
							(start -0.1524 0.10795)
							(mid -0.098518 0.130268)
							(end -0.0762 0.18415)
						)
						(xy -0.0762 0.22225) (xy 0.0762 0.22225)
						(arc
							(start 0.0762 0.18415)
							(mid 0.098518 0.130268)
							(end 0.1524 0.10795)
						)
						(xy 0.1524 -0.22225) (xy -0.1524 -0.22225)
					)
					(width 0)
					(fill yes)
				)
			)
		)
		(pad "2" smd custom
			(at 0 0.5334 90)
			(size 0.0762 0.0762)
			(layers "B.Cu" "B.Mask" "B.Paste")
			(net "PVDDQ_GHJ")
			(options
				(clearance outline)
				(anchor circle)
			)
			(primitives
				(gr_poly
					(pts
						(arc
							(start -0.1524 0.10795)
							(mid -0.098518 0.130268)
							(end -0.0762 0.18415)
						)
						(xy -0.0762 0.22225) (xy 0.0762 0.22225)
						(arc
							(start 0.0762 0.18415)
							(mid 0.098518 0.130268)
							(end 0.1524 0.10795)
						)
						(xy 0.1524 -0.22225) (xy -0.1524 -0.22225)
					)
					(width 0)
					(fill yes)
				)
			)
		)
	)
	(footprint ""
		(layer "B.Cu")
		(at 378.46 -83.4644 180)
		(property "Reference" "R7W3"
			(at 0.8382 -0.67818 180)
			(unlocked yes)
			(layer "B.SilkS")
			(effects
				(font
					(size 0.4064 0.254)
					(thickness 0.1524)
				)
				(justify left mirror)
			)
		)
		(property "Value" ""
			(at 0 0 0)
			(layer "B.Fab")
			(effects
				(font
					(size 1.27 1.27)
				)
				(justify mirror)
			)
		)
		(duplicate_pad_numbers_are_jumpers no)
		(fp_poly
			(pts
				(xy 0.2794 -0.1016) (xy -0.2794 -0.1016) (xy -0.2794 0.9906) (xy 0.2794 0.9906)
			)
			(stroke
				(width 0)
				(type default)
			)
			(fill no)
			(layer "B.CrtYd")
		)
		(fp_line
			(start 0.2794 0.9906)
			(end -0.2794 0.9906)
			(stroke
				(width 0.1)
				(type default)
			)
			(layer "B.Fab")
		)
		(fp_line
			(start 0.2794 -0.1016)
			(end 0.2794 0.9906)
			(stroke
				(width 0.1)
				(type default)
			)
			(layer "B.Fab")
		)
		(fp_line
			(start -0.2794 0.9906)
			(end -0.2794 -0.1016)
			(stroke
				(width 0.1)
				(type default)
			)
			(layer "B.Fab")
		)
		(fp_line
			(start -0.2794 -0.1016)
			(end 0.2794 -0.1016)
			(stroke
				(width 0.1)
				(type default)
			)
			(layer "B.Fab")
		)
		(pad "1" smd rect
			(at 0 0)
			(size 0.508 0.508)
			(layers "B.Cu" "B.Mask" "B.Paste")
			(net "P3V3_STBY")
		)
		(pad "2" smd rect
			(at 0 0.889)
			(size 0.508 0.508)
			(layers "B.Cu" "B.Mask" "B.Paste")
			(net "PECI_SEL")
		)
		(zone
			(layer "B.Cu")
			(hatch none 0.5)
			(connect_pads
				(clearance 0)
			)
			(min_thickness 0.25)
			(keepout
				(tracks not_allowed)
				(vias allowed)
				(pads allowed)
				(copperpour not_allowed)
				(footprints allowed)
			)
			(placement
				(enabled no)
				(sheetname "")
			)
			(fill
				(thermal_gap 0.5)
				(thermal_bridge_width 0.5)
				(island_removal_mode 0)
			)
			(polygon
				(pts
					(xy 378.206 -84.0994) (xy 378.714 -84.0994) (xy 378.714 -83.7184) (xy 378.206 -83.7184)
				)
			)
		)
		(zone
			(layer "B.Cu")
			(hatch none 0.5)
			(connect_pads
				(clearance 0)
			)
			(min_thickness 0.25)
			(keepout
				(tracks allowed)
				(vias not_allowed)
				(pads allowed)
				(copperpour not_allowed)
				(footprints allowed)
			)
			(placement
				(enabled no)
				(sheetname "")
			)
			(fill
				(thermal_gap 0.5)
				(thermal_bridge_width 0.5)
				(island_removal_mode 0)
			)
			(polygon
				(pts
					(xy 378.206 -83.7184) (xy 378.714 -83.7184) (xy 378.714 -84.0994) (xy 378.206 -84.0994)
				)
			)
		)
	)
)
